(kicad_pcb
	(version 20241229)
	(generator "pcbnew")
	(generator_version "9.0")
	(general
		(thickness 1.711)
		(legacy_teardrops no)
	)
	(paper "A4")
	(title_block
		(title "Antmicro Baseboard for Jetson AGX Thor")
		(date "2026-02-18")
		(rev "1.1.0")
		(company "Antmicro Ltd")
		(comment 1 "www.antmicro.com")
		(comment 9 "footprints 915-919 of 1170")
	)
	(layers
		(0 "F.Cu" signal)
		(4 "In1.Cu" signal)
		(6 "In2.Cu" signal)
		(8 "In3.Cu" signal)
		(10 "In4.Cu" jumper)
		(12 "In5.Cu" signal)
		(14 "In6.Cu" signal)
		(16 "In7.Cu" signal)
		(18 "In8.Cu" signal)
		(2 "B.Cu" signal)
		(9 "F.Adhes" user "F.Adhesive")
		(11 "B.Adhes" user "B.Adhesive")
		(13 "F.Paste" user)
		(15 "B.Paste" user)
		(5 "F.SilkS" user "F.Silkscreen")
		(7 "B.SilkS" user "B.Silkscreen")
		(1 "F.Mask" user)
		(3 "B.Mask" user)
		(17 "Dwgs.User" user "User.Drawings")
		(19 "Cmts.User" user "User.Comments")
		(21 "Eco1.User" user "User.Eco1")
		(23 "Eco2.User" user "User.Eco2")
		(25 "Edge.Cuts" user)
		(27 "Margin" user)
		(31 "F.CrtYd" user "F.Courtyard")
		(29 "B.CrtYd" user "B.Courtyard")
		(35 "F.Fab" user)
		(33 "B.Fab" user)
	)
	(footprint "antmicro-footprints:R_0402_1005Metric"
		(layer "B.Cu")
		(at 221.3 95.392 180)
		(descr "Resistor SMD 0402")
		(tags "resistor SMD 0402")
		(property "Reference" "R272"
			(at -1.122484 0.592 0)
			(layer "B.SilkS")
			(effects
				(font
					(size 0.7 0.7)
					(thickness 0.15)
				)
				(justify left bottom mirror)
			)
		)
		(property "Value" "R_100k_0402"
			(at -1.011843 -1.772047 0)
			(layer "B.Fab")
			(effects
				(font
					(size 0.7 0.7)
					(thickness 0.15)
				)
				(justify left bottom mirror)
			)
		)
		(property "Datasheet" "https://www.bourns.com/docs/product-datasheets/cr.pdf"
			(at 0 0 0)
			(layer "B.Fab")
			(hide yes)
			(effects
				(font
					(size 1.27 1.27)
					(thickness 0.15)
				)
				(justify mirror)
			)
		)
		(property "Description" "SMD Chip Resistor, 100 kohm, ± 1%, 62.5 mW, 0402 [1005 Metric], Thick Film, General Purpose"
			(at 0 0 0)
			(layer "B.Fab")
			(hide yes)
			(effects
				(font
					(size 1.27 1.27)
					(thickness 0.15)
				)
				(justify mirror)
			)
		)
		(property "Manufacturer" "Bourns"
			(at 0 0 0)
			(unlocked yes)
			(layer "B.Fab")
			(hide yes)
			(effects
				(font
					(size 1 1)
					(thickness 0.15)
				)
				(justify mirror)
			)
		)
		(property "MPN" "CR0402-FX-1003GLF"
			(at 0 0 0)
			(unlocked yes)
			(layer "B.Fab")
			(hide yes)
			(effects
				(font
					(size 1 1)
					(thickness 0.15)
				)
				(justify mirror)
			)
		)
		(property "Val" "100k"
			(at 0 0 0)
			(unlocked yes)
			(layer "B.Fab")
			(hide yes)
			(effects
				(font
					(size 1 1)
					(thickness 0.15)
				)
				(justify mirror)
			)
		)
		(property "License" "Apache-2.0"
			(at 0 0 0)
			(unlocked yes)
			(layer "B.Fab")
			(hide yes)
			(effects
				(font
					(size 1 1)
					(thickness 0.15)
				)
				(justify mirror)
			)
		)
		(property "Author" "Antmicro"
			(at 0 0 0)
			(unlocked yes)
			(layer "B.Fab")
			(hide yes)
			(effects
				(font
					(size 1 1)
					(thickness 0.15)
				)
				(justify mirror)
			)
		)
		(property "Tolerance" "1%"
			(at 0 0 0)
			(unlocked yes)
			(layer "B.Fab")
			(hide yes)
			(effects
				(font
					(size 1 1)
					(thickness 0.15)
				)
				(justify mirror)
			)
		)
		(sheetname "/USB DP Alt mode/")
		(sheetfile "usb_dp.kicad_sch")
		(attr smd)
		(fp_rect
			(start -0.925 0.47)
			(end 0.925 -0.47)
			(stroke
				(width 0.05)
				(type default)
			)
			(fill no)
			(layer "B.CrtYd")
		)
		(fp_rect
			(start -0.5 0.25)
			(end 0.5 -0.25)
			(stroke
				(width 0.15)
				(type solid)
			)
			(fill no)
			(layer "B.Fab")
		)
		(fp_text user "License: Apache-2.0"
			(at -0.95 -5.169 0)
			(layer "B.Fab")
			(effects
				(font
					(size 0.7 0.7)
					(thickness 0.15)
				)
				(justify left bottom mirror)
			)
		)
		(fp_text user "${REFERENCE}"
			(at -0.95 -3.168 0)
			(layer "B.Fab")
			(effects
				(font
					(size 0.7 0.7)
					(thickness 0.15)
				)
				(justify left bottom mirror)
			)
		)
		(fp_text user "Author: Antmicro"
			(at -0.95 -4.169 0)
			(layer "B.Fab")
			(effects
				(font
					(size 0.7 0.7)
					(thickness 0.15)
				)
				(justify left bottom mirror)
			)
		)
		(pad "1" smd roundrect
			(at -0.48 0 180)
			(size 0.59 0.64)
			(layers "B.Cu" "B.Mask" "B.Paste")
			(roundrect_rratio 0.25)
			(net 957 "/USB DP Alt mode/HPDIN")
			(pintype "passive")
		)
		(pad "2" smd roundrect
			(at 0.48 0 180)
			(size 0.59 0.64)
			(layers "B.Cu" "B.Mask" "B.Paste")
			(roundrect_rratio 0.25)
			(net 1 "GND")
			(pintype "passive")
		)
	)
	(footprint "antmicro-footprints:C_0603_1608Metric_EIA"
		(layer "B.Cu")
		(at 107.08 69.48 180)
		(descr "Capacitor SMD 0603, IPC-7351 Density Level A")
		(tags "Capacitor 0603")
		(property "Reference" "C7"
			(at -0.92 0.88 0)
			(layer "B.SilkS")
			(effects
				(font
					(size 0.7 0.7)
					(thickness 0.15)
				)
				(justify left bottom mirror)
			)
		)
		(property "Value" "C_22u_16V_0603"
			(at -1.42757 -1.770288 0)
			(layer "B.Fab")
			(effects
				(font
					(size 0.7 0.7)
					(thickness 0.15)
				)
				(justify left bottom mirror)
			)
		)
		(property "Datasheet" "https://product.samsungsem.com/mlcc/CL10A226MO7JZN.do"
			(at 0 0 0)
			(layer "B.Fab")
			(hide yes)
			(effects
				(font
					(size 1.27 1.27)
					(thickness 0.15)
				)
				(justify mirror)
			)
		)
		(property "Description" "SMD Multilayer Ceramic Capacitor"
			(at 0 0 0)
			(layer "B.Fab")
			(hide yes)
			(effects
				(font
					(size 1.27 1.27)
					(thickness 0.15)
				)
				(justify mirror)
			)
		)
		(property "MPN" "CL10A226MO7JZNC"
			(at 0 0 0)
			(unlocked yes)
			(layer "B.Fab")
			(hide yes)
			(effects
				(font
					(size 1 1)
					(thickness 0.15)
				)
				(justify mirror)
			)
		)
		(property "Manufacturer" "Samsung Electro-Mechanics"
			(at 0 0 0)
			(unlocked yes)
			(layer "B.Fab")
			(hide yes)
			(effects
				(font
					(size 1 1)
					(thickness 0.15)
				)
				(justify mirror)
			)
		)
		(property "License" "Apache-2.0"
			(at 0 0 0)
			(unlocked yes)
			(layer "B.Fab")
			(hide yes)
			(effects
				(font
					(size 1 1)
					(thickness 0.15)
				)
				(justify mirror)
			)
		)
		(property "Author" "Antmicro"
			(at 0 0 0)
			(unlocked yes)
			(layer "B.Fab")
			(hide yes)
			(effects
				(font
					(size 1 1)
					(thickness 0.15)
				)
				(justify mirror)
			)
		)
		(property "Val" "22u"
			(at 0 0 0)
			(unlocked yes)
			(layer "B.Fab")
			(hide yes)
			(effects
				(font
					(size 1 1)
					(thickness 0.15)
				)
				(justify mirror)
			)
		)
		(property "Voltage" "16V"
			(at 0 0 0)
			(unlocked yes)
			(layer "B.Fab")
			(hide yes)
			(effects
				(font
					(size 1 1)
					(thickness 0.15)
				)
				(justify mirror)
			)
		)
		(property "Dielectric" "X7R"
			(at 0 0 0)
			(unlocked yes)
			(layer "B.Fab")
			(hide yes)
			(effects
				(font
					(size 1 1)
					(thickness 0.15)
				)
				(justify mirror)
			)
		)
		(property "Public" "False"
			(at 0 0 0)
			(unlocked yes)
			(layer "B.Fab")
			(hide yes)
			(effects
				(font
					(size 1 1)
					(thickness 0.15)
				)
				(justify mirror)
			)
		)
		(sheetname "/SoM_Power/")
		(sheetfile "som_power.kicad_sch")
		(attr smd)
		(fp_line
			(start -0.15 0.55)
			(end 0.15 0.55)
			(stroke
				(width 0.15)
				(type solid)
			)
			(layer "B.SilkS")
		)
		(fp_line
			(start -0.15 -0.55)
			(end 0.15 -0.55)
			(stroke
				(width 0.15)
				(type solid)
			)
			(layer "B.SilkS")
		)
		(fp_rect
			(start -1.25 0.65)
			(end 1.25 -0.65)
			(stroke
				(width 0.05)
				(type solid)
			)
			(fill no)
			(layer "B.CrtYd")
		)
		(fp_rect
			(start -0.8 0.45)
			(end 0.8 -0.45)
			(stroke
				(width 0.15)
				(type solid)
			)
			(fill no)
			(layer "B.Fab")
		)
		(fp_text user "${REFERENCE}"
			(at -1.682 -3.895 0)
			(layer "B.Fab")
			(effects
				(font
					(size 0.7 0.7)
					(thickness 0.15)
				)
				(justify left bottom mirror)
			)
		)
		(fp_text user "Author: Antmicro"
			(at -1.682 -4.894 0)
			(layer "B.Fab")
			(effects
				(font
					(size 0.7 0.7)
					(thickness 0.15)
				)
				(justify left bottom mirror)
			)
		)
		(fp_text user "License: Apache-2.0"
			(at -1.682 -5.895 0)
			(layer "B.Fab")
			(effects
				(font
					(size 0.7 0.7)
					(thickness 0.15)
				)
				(justify left bottom mirror)
			)
		)
		(pad "1" smd roundrect
			(at -0.7 0 180)
			(size 0.8 1.1)
			(layers "B.Cu" "B.Mask" "B.Paste")
			(roundrect_rratio 0.2)
			(net 1 "GND")
			(pintype "passive")
		)
		(pad "2" smd roundrect
			(at 0.7 0 180)
			(size 0.8 1.1)
			(layers "B.Cu" "B.Mask" "B.Paste")
			(roundrect_rratio 0.2)
			(net 213 "+5V_SOM")
			(pintype "passive")
		)
	)
	(footprint "antmicro-footprints:R_0402_1005Metric"
		(layer "B.Cu")
		(at 212.8 91.8)
		(descr "Resistor SMD 0402")
		(tags "resistor SMD 0402")
		(property "Reference" "R129"
			(at -3.9 -0.3 0)
			(layer "B.SilkS")
			(effects
				(font
					(size 0.7 0.7)
					(thickness 0.15)
				)
				(justify right top mirror)
			)
		)
		(property "Value" "R_1k_0402"
			(at -1.011843 -1.772046 0)
			(layer "B.Fab")
			(effects
				(font
					(size 0.7 0.7)
					(thickness 0.15)
				)
				(justify right top mirror)
			)
		)
		(property "Datasheet" "https://www.bourns.com/docs/product-datasheets/cr.pdf"
			(at 0 0 0)
			(layer "B.Fab")
			(hide yes)
			(effects
				(font
					(size 1.27 1.27)
					(thickness 0.15)
				)
				(justify mirror)
			)
		)
		(property "Description" "SMD Chip Resistor, 1 kohm, ± 1%, 63 mW, 0402 [1005 Metric], Thick Film, General Purpose"
			(at 0 0 0)
			(layer "B.Fab")
			(hide yes)
			(effects
				(font
					(size 1.27 1.27)
					(thickness 0.15)
				)
				(justify mirror)
			)
		)
		(property "Manufacturer" "Bourns"
			(at 0 0 180)
			(unlocked yes)
			(layer "B.Fab")
			(hide yes)
			(effects
				(font
					(size 1 1)
					(thickness 0.15)
				)
				(justify mirror)
			)
		)
		(property "MPN" "CR0402-FX-1001GLF"
			(at 0 0 180)
			(unlocked yes)
			(layer "B.Fab")
			(hide yes)
			(effects
				(font
					(size 1 1)
					(thickness 0.15)
				)
				(justify mirror)
			)
		)
		(property "Val" "1k"
			(at 0 0 180)
			(unlocked yes)
			(layer "B.Fab")
			(hide yes)
			(effects
				(font
					(size 1 1)
					(thickness 0.15)
				)
				(justify mirror)
			)
		)
		(property "License" "Apache-2.0"
			(at 0 0 180)
			(unlocked yes)
			(layer "B.Fab")
			(hide yes)
			(effects
				(font
					(size 1 1)
					(thickness 0.15)
				)
				(justify mirror)
			)
		)
		(property "Author" "Antmicro"
			(at 0 0 180)
			(unlocked yes)
			(layer "B.Fab")
			(hide yes)
			(effects
				(font
					(size 1 1)
					(thickness 0.15)
				)
				(justify mirror)
			)
		)
		(property "Tolerance" "1%"
			(at 0 0 180)
			(unlocked yes)
			(layer "B.Fab")
			(hide yes)
			(effects
				(font
					(size 1 1)
					(thickness 0.15)
				)
				(justify mirror)
			)
		)
		(sheetname "/USB DP Alt mode/")
		(sheetfile "usb_dp.kicad_sch")
		(attr smd)
		(fp_poly
			(pts
				(xy -0.925 0.47) (xy 0.925 0.47) (xy 0.925 -0.47) (xy -0.925 -0.47)
			)
			(stroke
				(width 0.05)
				(type default)
			)
			(fill no)
			(layer "B.CrtYd")
		)
		(fp_poly
			(pts
				(xy -0.5 0.25) (xy 0.5 0.25) (xy 0.5 -0.25) (xy -0.5 -0.25)
			)
			(stroke
				(width 0.15)
				(type solid)
			)
			(fill no)
			(layer "B.Fab")
		)
		(fp_text user "Author: Antmicro"
			(at -0.95 -4.169 0)
			(layer "B.Fab")
			(effects
				(font
					(size 0.7 0.7)
					(thickness 0.15)
				)
				(justify right top mirror)
			)
		)
		(fp_text user "License: Apache-2.0"
			(at -0.949999 -5.169 0)
			(layer "B.Fab")
			(effects
				(font
					(size 0.7 0.7)
					(thickness 0.15)
				)
				(justify right top mirror)
			)
		)
		(fp_text user "${REFERENCE}"
			(at -0.95 -3.168 0)
			(layer "B.Fab")
			(effects
				(font
					(size 0.7 0.7)
					(thickness 0.15)
				)
				(justify right top mirror)
			)
		)
		(pad "1" smd roundrect
			(at -0.48 0)
			(size 0.59 0.64)
			(layers "B.Cu" "B.Mask" "B.Paste")
			(roundrect_rratio 0.25)
			(net 963 "/USB DP Alt mode/USBC1_I2C_EN")
			(pintype "passive")
		)
		(pad "2" smd roundrect
			(at 0.48 0)
			(size 0.59 0.64)
			(layers "B.Cu" "B.Mask" "B.Paste")
			(roundrect_rratio 0.25)
			(net 1 "GND")
			(pintype "passive")
		)
	)
	(footprint "antmicro-footprints:R_0402_1005Metric"
		(layer "B.Cu")
		(at 220.4 124.4)
		(descr "Resistor SMD 0402")
		(tags "resistor SMD 0402")
		(property "Reference" "R337"
			(at -0.9 1.708302 0)
			(layer "B.SilkS")
			(effects
				(font
					(size 0.7 0.7)
					(thickness 0.15)
				)
				(justify right top mirror)
			)
		)
		(property "Value" "R_2R2_0402"
			(at -1.011843 -1.772047 0)
			(layer "B.Fab")
			(effects
				(font
					(size 0.7 0.7)
					(thickness 0.15)
				)
				(justify right top mirror)
			)
		)
		(property "Datasheet" "https://www.bourns.com/docs/product-datasheets/cr.pdf"
			(at 0 0 0)
			(layer "B.Fab")
			(hide yes)
			(effects
				(font
					(size 1.27 1.27)
					(thickness 0.15)
				)
				(justify mirror)
			)
		)
		(property "Description" "SMD Chip Resistor, 2.2 ohm, ± 1%, 62.5 mW, 0402 [1005 Metric], Thick Film, General Purpose"
			(at 0 0 0)
			(layer "B.Fab")
			(hide yes)
			(effects
				(font
					(size 1.27 1.27)
					(thickness 0.15)
				)
				(justify mirror)
			)
		)
		(property "MPN" "CR0402-FX-2R20GLF"
			(at 0 0 180)
			(unlocked yes)
			(layer "B.Fab")
			(hide yes)
			(effects
				(font
					(size 1 1)
					(thickness 0.15)
				)
				(justify mirror)
			)
		)
		(property "Manufacturer" "Bourns"
			(at 0 0 180)
			(unlocked yes)
			(layer "B.Fab")
			(hide yes)
			(effects
				(font
					(size 1 1)
					(thickness 0.15)
				)
				(justify mirror)
			)
		)
		(property "License" "Apache-2.0"
			(at 0 0 180)
			(unlocked yes)
			(layer "B.Fab")
			(hide yes)
			(effects
				(font
					(size 1 1)
					(thickness 0.15)
				)
				(justify mirror)
			)
		)
		(property "Author" "Antmicro"
			(at 0 0 180)
			(unlocked yes)
			(layer "B.Fab")
			(hide yes)
			(effects
				(font
					(size 1 1)
					(thickness 0.15)
				)
				(justify mirror)
			)
		)
		(property "Val" "2R2"
			(at 0 0 180)
			(unlocked yes)
			(layer "B.Fab")
			(hide yes)
			(effects
				(font
					(size 1 1)
					(thickness 0.15)
				)
				(justify mirror)
			)
		)
		(property "Tolerance" "1%"
			(at 0 0 180)
			(unlocked yes)
			(layer "B.Fab")
			(hide yes)
			(effects
				(font
					(size 1 1)
					(thickness 0.15)
				)
				(justify mirror)
			)
		)
		(sheetname "/USB Hub/")
		(sheetfile "usb_hub.kicad_sch")
		(attr smd)
		(fp_rect
			(start -0.925 0.47)
			(end 0.925 -0.47)
			(stroke
				(width 0.05)
				(type default)
			)
			(fill no)
			(layer "B.CrtYd")
		)
		(fp_rect
			(start -0.5 0.25)
			(end 0.5 -0.25)
			(stroke
				(width 0.15)
				(type solid)
			)
			(fill no)
			(layer "B.Fab")
		)
		(fp_text user "License: Apache-2.0"
			(at -0.95 -5.169 0)
			(layer "B.Fab")
			(effects
				(font
					(size 0.7 0.7)
					(thickness 0.15)
				)
				(justify right top mirror)
			)
		)
		(fp_text user "Author: Antmicro"
			(at -0.95 -4.169 0)
			(layer "B.Fab")
			(effects
				(font
					(size 0.7 0.7)
					(thickness 0.15)
				)
				(justify right top mirror)
			)
		)
		(fp_text user "${REFERENCE}"
			(at -0.95 -3.168 0)
			(layer "B.Fab")
			(effects
				(font
					(size 0.7 0.7)
					(thickness 0.15)
				)
				(justify right top mirror)
			)
		)
		(pad "1" smd roundrect
			(at -0.48 0)
			(size 0.59 0.64)
			(layers "B.Cu" "B.Mask" "B.Paste")
			(roundrect_rratio 0.25)
			(net 1241 "Net-(D60-C)")
			(pintype "passive")
		)
		(pad "2" smd roundrect
			(at 0.48 0)
			(size 0.59 0.64)
			(layers "B.Cu" "B.Mask" "B.Paste")
			(roundrect_rratio 0.25)
			(net 502 "/USB Hub/USBC4_CC_{2}")
			(pintype "passive")
		)
	)
	(footprint "antmicro-footprints:TP_SMD_0.75mm"
		(layer "B.Cu")
		(at 134 150.1 -90)
		(property "Reference" "TP95"
			(at -3.3 -0.5 90)
			(layer "B.SilkS")
			(effects
				(font
					(size 0.7 0.7)
					(thickness 0.15)
				)
				(justify left bottom mirror)
			)
		)
		(property "Value" "TP_0.75mm_SMD"
			(at 0 -1.2 90)
			(layer "B.Fab")
			(effects
				(font
					(size 0.7 0.7)
					(thickness 0.15)
				)
				(justify left bottom mirror)
			)
		)
		(property "Description" "SMT test point"
			(at 0 0 90)
			(layer "B.Fab")
			(hide yes)
			(effects
				(font
					(size 1.27 1.27)
					(thickness 0.15)
				)
				(justify mirror)
			)
		)
		(property "MPN" ""
			(at 0 0 90)
			(unlocked yes)
			(layer "B.Fab")
			(hide yes)
			(effects
				(font
					(size 1 1)
					(thickness 0.15)
				)
				(justify mirror)
			)
		)
		(property "Manufacturer" ""
			(at 0 0 90)
			(unlocked yes)
			(layer "B.Fab")
			(hide yes)
			(effects
				(font
					(size 1 1)
					(thickness 0.15)
				)
				(justify mirror)
			)
		)
		(property "Author" "Antmicro"
			(at 0 0 90)
			(unlocked yes)
			(layer "B.Fab")
			(hide yes)
			(effects
				(font
					(size 1 1)
					(thickness 0.15)
				)
				(justify mirror)
			)
		)
		(property "License" "Apache-2.0"
			(at 0 0 90)
			(unlocked yes)
			(layer "B.Fab")
			(hide yes)
			(effects
				(font
					(size 1 1)
					(thickness 0.15)
				)
				(justify mirror)
			)
		)
		(sheetname "/Peripherals/")
		(sheetfile "peripherals.kicad_sch")
		(attr exclude_from_pos_files exclude_from_bom)
		(fp_circle
			(center 0 0)
			(end 0.475 0)
			(stroke
				(width 0.05)
				(type default)
			)
			(fill no)
			(layer "B.CrtYd")
		)
		(fp_text user "Author: Antmicro"
			(at -0.4 -3.901 90)
			(layer "B.Fab")
			(effects
				(font
					(size 0.7 0.7)
					(thickness 0.15)
				)
				(justify left bottom mirror)
			)
		)
		(fp_text user "${REFERENCE}"
			(at -0.4 -2.7 90)
			(layer "B.Fab")
			(effects
				(font
					(size 0.7 0.7)
					(thickness 0.15)
				)
				(justify left bottom mirror)
			)
		)
		(fp_text user "License: Apache-2.0"
			(at -0.4 -5.101 90)
			(layer "B.Fab")
			(effects
				(font
					(size 0.7 0.7)
					(thickness 0.15)
				)
				(justify left bottom mirror)
			)
		)
		(pad "1" smd circle
			(at 0 0 270)
			(size 0.75 0.75)
			(layers "B.Cu" "B.Mask")
			(net 1100 "/Peripherals/TPM_RST")
			(pinfunction "1")
			(pintype "passive")
		)
	)
)
